(kicad_pcb
	(version 20260206)
	(generator "pcbnew")
	(generator_version "10.0")
	(general
		(thickness 1.6)
		(legacy_teardrops no)
	)
	(paper "A4")
	(title_block
		(title "dpb — 14545-sa.0730WZS0815.brd")
		(comment 1 "Honey Badger (Wiwynn) / footprints 56-64 of 1066")
	)
	(layers
		(0 "F.Cu" signal "TOP")
		(4 "In1.Cu" signal "L2GND")
		(6 "In2.Cu" signal "L3")
		(8 "In3.Cu" signal "L4VCC")
		(10 "In4.Cu" signal "L5VCC")
		(12 "In5.Cu" signal "L6")
		(14 "In6.Cu" signal "L7GND")
		(2 "B.Cu" signal "BOTTOM")
		(9 "F.Adhes" user "F.Adhesive")
		(11 "B.Adhes" user "B.Adhesive")
		(13 "F.Paste" user "Package Geometry/Pastemask Top")
		(15 "B.Paste" user "Package Geometry/Pastemask Bottom")
		(5 "F.SilkS" user "Ref Des/Silkscreen Top")
		(7 "B.SilkS" user "Ref Des/Silkscreen Bottom")
		(1 "F.Mask" user "Board Geometry/Soldermask Top")
		(3 "B.Mask" user "Board Geometry/Soldermask Bottom")
		(17 "Dwgs.User" user "User.Drawings")
		(19 "Cmts.User" user "User.Comments")
		(21 "Eco1.User" user "User.Eco1")
		(23 "Eco2.User" user "User.Eco2")
		(25 "Edge.Cuts" user "Board Geometry/Outline")
		(27 "Margin" user)
		(31 "F.CrtYd" user "Package Geometry/Place Bound Top")
		(29 "B.CrtYd" user "Package Geometry/Place Bound Bottom")
		(35 "F.Fab" user "Ref Des/Assembly Top")
		(33 "B.Fab" user "Ref Des/Assembly Bottom")
	)
	(footprint ""
		(layer "F.Cu")
		(at 44.068746 -221.770702 90)
		(property "Reference" "R276"
			(at 0 0 90)
			(layer "F.SilkS")
			(hide yes)
			(effects
				(font
					(size 1.27 1.27)
				)
			)
		)
		(property "Value" "2R2010J-1-GP"
			(at 0.254 -8.0772 90)
			(unlocked yes)
			(layer "F.Fab")
			(hide yes)
			(effects
				(font
					(size 1.016 1.016)
					(thickness 0.1524)
				)
			)
		)
		(property "Device Type" "R2010H28"
			(at 0.254 -9.6774 90)
			(unlocked yes)
			(layer "F.Fab")
			(hide yes)
			(effects
				(font
					(size 1.016 1.016)
					(thickness 0.1524)
				)
			)
		)
		(duplicate_pad_numbers_are_jumpers no)
		(fp_line
			(start 1.651 -3.302)
			(end -1.651 -3.302)
			(stroke
				(width 0.1524)
				(type default)
			)
			(layer "F.SilkS")
		)
		(fp_line
			(start -1.651 -3.302)
			(end -1.651 3.302)
			(stroke
				(width 0.1524)
				(type default)
			)
			(layer "F.SilkS")
		)
		(fp_line
			(start 1.651 3.302)
			(end 1.651 -3.302)
			(stroke
				(width 0.1524)
				(type default)
			)
			(layer "F.SilkS")
		)
		(fp_line
			(start -1.651 3.302)
			(end 1.651 3.302)
			(stroke
				(width 0.1524)
				(type default)
			)
			(layer "F.SilkS")
		)
		(fp_rect
			(start -1.7272 -3.3782)
			(end 1.7272 3.3782)
			(stroke
				(width 0)
				(type default)
			)
			(fill no)
			(layer "F.CrtYd")
		)
		(fp_poly
			(pts
				(xy 1.7272 3.3782) (xy 1.7272 -3.3782) (xy -1.7272 -3.3782) (xy -1.7272 3.3782)
			)
			(stroke
				(width 0)
				(type default)
			)
			(fill no)
			(layer "F.Fab")
		)
		(pad "1" smd rect
			(at 0 -2.3495 90)
			(size 2.794 1.143)
			(layers "F.Cu" "F.Mask" "F.Paste")
			(net "12V_PRE_12")
		)
		(pad "2" smd rect
			(at 0 2.3495 90)
			(size 2.794 1.143)
			(layers "F.Cu" "F.Mask" "F.Paste")
			(net "P12V_HDD12")
		)
	)
	(footprint ""
		(layer "F.Cu")
		(at 70.738746 -396.5067)
		(property "Reference" "R446"
			(at 0 0 0)
			(layer "F.SilkS")
			(hide yes)
			(effects
				(font
					(size 1.27 1.27)
				)
			)
		)
		(property "Value" "4K7R2J-2-GP"
			(at 0.064008 -3.993896 0)
			(unlocked yes)
			(layer "F.Fab")
			(hide yes)
			(effects
				(font
					(size 1.016 1.016)
					(thickness 0.1524)
				)
			)
		)
		(property "Device Type" "R402H16"
			(at 0.064008 -5.517896 0)
			(unlocked yes)
			(layer "F.Fab")
			(hide yes)
			(effects
				(font
					(size 1.016 1.016)
					(thickness 0.1524)
				)
			)
		)
		(duplicate_pad_numbers_are_jumpers no)
		(fp_line
			(start -0.508 -0.9398)
			(end -0.508 0.9398)
			(stroke
				(width 0.1524)
				(type default)
			)
			(layer "F.SilkS")
		)
		(fp_line
			(start 0.508 -0.9398)
			(end -0.508 -0.9398)
			(stroke
				(width 0.1524)
				(type default)
			)
			(layer "F.SilkS")
		)
		(fp_rect
			(start -0.508 0.9398)
			(end 0.508 -0.9398)
			(stroke
				(width 0)
				(type default)
			)
			(fill no)
			(layer "F.CrtYd")
		)
		(fp_rect
			(start -0.508 0.9398)
			(end 0.508 -0.9398)
			(stroke
				(width 0)
				(type default)
			)
			(fill no)
			(layer "F.Fab")
		)
		(pad "1" smd custom
			(at 0 -0.4445)
			(size 0.1397 0.1397)
			(layers "F.Cu" "F.Mask" "F.Paste")
			(net "P3V3")
			(options
				(clearance outline)
				(anchor circle)
			)
			(primitives
				(gr_poly
					(pts
						(arc
							(start -0.1778 -0.2794)
							(mid -0.249642 -0.249642)
							(end -0.2794 -0.1778)
						)
						(arc
							(start -0.2794 0.1778)
							(mid -0.249642 0.249642)
							(end -0.1778 0.2794)
						)
						(arc
							(start 0.1778 0.2794)
							(mid 0.249642 0.249642)
							(end 0.2794 0.1778)
						)
						(arc
							(start 0.2794 -0.1778)
							(mid 0.249642 -0.249642)
							(end 0.1778 -0.2794)
						)
					)
					(width 0)
					(fill yes)
				)
			)
		)
		(pad "2" smd custom
			(at 0 0.4445)
			(size 0.1397 0.1397)
			(layers "F.Cu" "F.Mask" "F.Paste")
			(net "SAS2X28_A_HDD6_FLT")
			(options
				(clearance outline)
				(anchor circle)
			)
			(primitives
				(gr_poly
					(pts
						(arc
							(start -0.1778 -0.2794)
							(mid -0.249642 -0.249642)
							(end -0.2794 -0.1778)
						)
						(arc
							(start -0.2794 0.1778)
							(mid -0.249642 0.249642)
							(end -0.1778 0.2794)
						)
						(arc
							(start 0.1778 0.2794)
							(mid 0.249642 0.249642)
							(end 0.2794 0.1778)
						)
						(arc
							(start 0.2794 -0.1778)
							(mid 0.249642 -0.249642)
							(end 0.1778 -0.2794)
						)
					)
					(width 0)
					(fill yes)
				)
			)
		)
	)
	(footprint ""
		(layer "F.Cu")
		(at 26.880312 -345.935808 90)
		(property "Reference" "C278"
			(at 0 0 90)
			(layer "F.SilkS")
			(hide yes)
			(effects
				(font
					(size 1.27 1.27)
				)
			)
		)
		(property "Value" "SCD01U50V2KX-1GP"
			(at 1.1811 -2.7051 90)
			(unlocked yes)
			(layer "F.Fab")
			(hide yes)
			(effects
				(font
					(size 1.016 1.016)
					(thickness 0.1524)
				)
			)
		)
		(property "Device Type" "C402H22"
			(at 1.1811 -4.2291 90)
			(unlocked yes)
			(layer "F.Fab")
			(hide yes)
			(effects
				(font
					(size 1.016 1.016)
					(thickness 0.1524)
				)
			)
		)
		(duplicate_pad_numbers_are_jumpers no)
		(fp_rect
			(start -0.4318 0.9525)
			(end 0.4318 -0.9525)
			(stroke
				(width 0)
				(type default)
			)
			(fill no)
			(layer "F.CrtYd")
		)
		(fp_rect
			(start -0.4318 0.9525)
			(end 0.4318 -0.9525)
			(stroke
				(width 0)
				(type default)
			)
			(fill no)
			(layer "F.Fab")
		)
		(pad "1" smd custom
			(at 0 -0.4445 90)
			(size 0.1524 0.1524)
			(layers "F.Cu" "F.Mask" "F.Paste")
			(net "SAS2X28_DRIVE_RX_N_A11")
			(options
				(clearance outline)
				(anchor circle)
			)
			(primitives
				(gr_poly
					(pts
						(arc
							(start 0.3048 -0.2032)
							(mid 0.275042 -0.275042)
							(end 0.2032 -0.3048)
						)
						(arc
							(start -0.2032 -0.3048)
							(mid -0.275042 -0.275042)
							(end -0.3048 -0.2032)
						)
						(arc
							(start -0.3048 0.2032)
							(mid -0.275042 0.275042)
							(end -0.2032 0.3048)
						)
						(arc
							(start 0.2032 0.3048)
							(mid 0.275042 0.275042)
							(end 0.3048 0.2032)
						)
					)
					(width 0)
					(fill yes)
				)
			)
		)
		(pad "2" smd custom
			(at 0 0.4445 90)
			(size 0.1524 0.1524)
			(layers "F.Cu" "F.Mask" "F.Paste")
			(net "SAS2X28_A_HDD11_RX_-")
			(options
				(clearance outline)
				(anchor circle)
			)
			(primitives
				(gr_poly
					(pts
						(arc
							(start 0.3048 -0.2032)
							(mid 0.275042 -0.275042)
							(end 0.2032 -0.3048)
						)
						(arc
							(start -0.2032 -0.3048)
							(mid -0.275042 -0.275042)
							(end -0.3048 -0.2032)
						)
						(arc
							(start -0.3048 0.2032)
							(mid -0.275042 0.275042)
							(end -0.2032 0.3048)
						)
						(arc
							(start 0.2032 0.3048)
							(mid 0.275042 0.275042)
							(end 0.3048 0.2032)
						)
					)
					(width 0)
					(fill yes)
				)
			)
		)
	)
	(footprint ""
		(layer "F.Cu")
		(at 59.2074 -490.1692)
		(property "Reference" "TP30"
			(at 0 0 0)
			(layer "F.SilkS")
			(hide yes)
			(effects
				(font
					(size 1.27 1.27)
				)
			)
		)
		(property "Value" "TPAD32-GP"
			(at 0 -3.166364 0)
			(unlocked yes)
			(layer "F.Fab")
			(hide yes)
			(effects
				(font
					(size 1.016 1.016)
					(thickness 0.1524)
				)
			)
		)
		(property "Device Type" "TPAD32"
			(at 0 -4.690618 0)
			(unlocked yes)
			(layer "F.Fab")
			(hide yes)
			(effects
				(font
					(size 1.016 1.016)
					(thickness 0.1524)
				)
			)
		)
		(duplicate_pad_numbers_are_jumpers no)
		(fp_poly
			(pts
				(arc
					(start 0.4064 0)
					(mid -0.4064 0)
					(end 0.4064 0)
				)
			)
			(stroke
				(width 0)
				(type default)
			)
			(fill no)
			(layer "F.CrtYd")
		)
		(fp_poly
			(pts
				(arc
					(start 0.7112 0)
					(mid -0.7112 0)
					(end 0.7112 0)
				)
			)
			(stroke
				(width 0)
				(type default)
			)
			(fill no)
			(layer "F.Fab")
		)
		(pad "1" smd circle
			(at 0 0)
			(size 0.8128 0.8128)
			(layers "F.Cu" "F.Mask" "F.Paste")
			(net "ACT_HDD5")
		)
	)
	(footprint ""
		(layer "F.Cu")
		(at 213.741 -181.102)
		(property "Reference" "TP28"
			(at 0 0 0)
			(layer "F.SilkS")
			(hide yes)
			(effects
				(font
					(size 1.27 1.27)
				)
			)
		)
		(property "Value" "TPAD32-GP"
			(at 0 -3.166364 0)
			(unlocked yes)
			(layer "F.Fab")
			(hide yes)
			(effects
				(font
					(size 1.016 1.016)
					(thickness 0.1524)
				)
			)
		)
		(property "Device Type" "TPAD32"
			(at 0 -4.690618 0)
			(unlocked yes)
			(layer "F.Fab")
			(hide yes)
			(effects
				(font
					(size 1.016 1.016)
					(thickness 0.1524)
				)
			)
		)
		(duplicate_pad_numbers_are_jumpers no)
		(fp_poly
			(pts
				(arc
					(start 0.4064 0)
					(mid -0.4064 0)
					(end 0.4064 0)
				)
			)
			(stroke
				(width 0)
				(type default)
			)
			(fill no)
			(layer "F.CrtYd")
		)
		(fp_poly
			(pts
				(arc
					(start 0.7112 0)
					(mid -0.7112 0)
					(end 0.7112 0)
				)
			)
			(stroke
				(width 0)
				(type default)
			)
			(fill no)
			(layer "F.Fab")
		)
		(pad "1" smd circle
			(at 0 0)
			(size 0.8128 0.8128)
			(layers "F.Cu" "F.Mask" "F.Paste")
			(net "ACT_HDD3")
		)
	)
	(footprint ""
		(layer "F.Cu")
		(at 4.445 -280.035 90)
		(property "Reference" "C124"
			(at 0 0 90)
			(layer "F.SilkS")
			(hide yes)
			(effects
				(font
					(size 1.27 1.27)
				)
			)
		)
		(property "Value" "SC1U25V3KX-1-GP"
			(at 0 -2.8194 90)
			(unlocked yes)
			(layer "F.Fab")
			(hide yes)
			(effects
				(font
					(size 1.016 1.016)
					(thickness 0.1524)
				)
			)
		)
		(property "Device Type" "C603H36"
			(at 0 -4.3434 90)
			(unlocked yes)
			(layer "F.Fab")
			(hide yes)
			(effects
				(font
					(size 1.016 1.016)
					(thickness 0.1524)
				)
			)
		)
		(duplicate_pad_numbers_are_jumpers no)
		(fp_line
			(start 0.508 0)
			(end -0.508 0)
			(stroke
				(width 0.2032)
				(type default)
			)
			(layer "F.SilkS")
		)
		(fp_rect
			(start -0.5842 1.3335)
			(end 0.5842 -1.3335)
			(stroke
				(width 0)
				(type default)
			)
			(fill no)
			(layer "F.CrtYd")
		)
		(fp_rect
			(start -0.5842 1.3335)
			(end 0.5842 -1.3335)
			(stroke
				(width 0)
				(type default)
			)
			(fill no)
			(layer "F.Fab")
		)
		(pad "1" smd custom
			(at 0 -0.762 90)
			(size 0.2159 0.2159)
			(layers "F.Cu" "F.Mask" "F.Paste")
			(net "P12V")
			(options
				(clearance outline)
				(anchor circle)
			)
			(primitives
				(gr_poly
					(pts
						(arc
							(start -0.3302 -0.4318)
							(mid -0.402042 -0.402042)
							(end -0.4318 -0.3302)
						)
						(arc
							(start -0.4318 0.3302)
							(mid -0.402042 0.402042)
							(end -0.3302 0.4318)
						)
						(arc
							(start 0.3302 0.4318)
							(mid 0.402042 0.402042)
							(end 0.4318 0.3302)
						)
						(arc
							(start 0.4318 -0.3302)
							(mid 0.402042 -0.402042)
							(end 0.3302 -0.4318)
						)
					)
					(width 0)
					(fill yes)
				)
			)
		)
		(pad "2" smd custom
			(at 0 0.762 90)
			(size 0.2159 0.2159)
			(layers "F.Cu" "F.Mask" "F.Paste")
			(net "GND")
			(options
				(clearance outline)
				(anchor circle)
			)
			(primitives
				(gr_poly
					(pts
						(arc
							(start -0.3302 -0.4318)
							(mid -0.402042 -0.402042)
							(end -0.4318 -0.3302)
						)
						(arc
							(start -0.4318 0.3302)
							(mid -0.402042 0.402042)
							(end -0.3302 0.4318)
						)
						(arc
							(start 0.3302 0.4318)
							(mid 0.402042 0.402042)
							(end 0.4318 0.3302)
						)
						(arc
							(start 0.4318 -0.3302)
							(mid 0.402042 -0.402042)
							(end 0.3302 -0.4318)
						)
					)
					(width 0)
					(fill yes)
				)
			)
		)
	)
	(footprint ""
		(layer "F.Cu")
		(at 53.339746 -228.603302)
		(property "Reference" "R469"
			(at 0 0 0)
			(layer "F.SilkS")
			(hide yes)
			(effects
				(font
					(size 1.27 1.27)
				)
			)
		)
		(property "Value" "4K7R2J-2-GP"
			(at 0.064008 -3.993896 0)
			(unlocked yes)
			(layer "F.Fab")
			(hide yes)
			(effects
				(font
					(size 1.016 1.016)
					(thickness 0.1524)
				)
			)
		)
		(property "Device Type" "R402H16"
			(at 0.064008 -5.517896 0)
			(unlocked yes)
			(layer "F.Fab")
			(hide yes)
			(effects
				(font
					(size 1.016 1.016)
					(thickness 0.1524)
				)
			)
		)
		(duplicate_pad_numbers_are_jumpers no)
		(fp_line
			(start -0.508 -0.9398)
			(end -0.508 0.9398)
			(stroke
				(width 0.1524)
				(type default)
			)
			(layer "F.SilkS")
		)
		(fp_line
			(start 0.508 -0.9398)
			(end -0.508 -0.9398)
			(stroke
				(width 0.1524)
				(type default)
			)
			(layer "F.SilkS")
		)
		(fp_rect
			(start -0.508 0.9398)
			(end 0.508 -0.9398)
			(stroke
				(width 0)
				(type default)
			)
			(fill no)
			(layer "F.CrtYd")
		)
		(fp_rect
			(start -0.508 0.9398)
			(end 0.508 -0.9398)
			(stroke
				(width 0)
				(type default)
			)
			(fill no)
			(layer "F.Fab")
		)
		(pad "1" smd custom
			(at 0 -0.4445)
			(size 0.1397 0.1397)
			(layers "F.Cu" "F.Mask" "F.Paste")
			(net "P3V3")
			(options
				(clearance outline)
				(anchor circle)
			)
			(primitives
				(gr_poly
					(pts
						(arc
							(start -0.1778 -0.2794)
							(mid -0.249642 -0.249642)
							(end -0.2794 -0.1778)
						)
						(arc
							(start -0.2794 0.1778)
							(mid -0.249642 0.249642)
							(end -0.1778 0.2794)
						)
						(arc
							(start 0.1778 0.2794)
							(mid 0.249642 0.249642)
							(end 0.2794 0.1778)
						)
						(arc
							(start 0.2794 -0.1778)
							(mid 0.249642 -0.249642)
							(end 0.1778 -0.2794)
						)
					)
					(width 0)
					(fill yes)
				)
			)
		)
		(pad "2" smd custom
			(at 0 0.4445)
			(size 0.1397 0.1397)
			(layers "F.Cu" "F.Mask" "F.Paste")
			(net "SAS2X28_B_HDD12_FLT")
			(options
				(clearance outline)
				(anchor circle)
			)
			(primitives
				(gr_poly
					(pts
						(arc
							(start -0.1778 -0.2794)
							(mid -0.249642 -0.249642)
							(end -0.2794 -0.1778)
						)
						(arc
							(start -0.2794 0.1778)
							(mid -0.249642 0.249642)
							(end -0.1778 0.2794)
						)
						(arc
							(start 0.1778 0.2794)
							(mid 0.249642 0.249642)
							(end 0.2794 0.1778)
						)
						(arc
							(start 0.2794 -0.1778)
							(mid 0.249642 -0.249642)
							(end 0.1778 -0.2794)
						)
					)
					(width 0)
					(fill yes)
				)
			)
		)
	)
	(footprint ""
		(layer "F.Cu")
		(at 27.812746 -433.225702 180)
		(property "Reference" "R251"
			(at 0 0 180)
			(layer "F.SilkS")
			(hide yes)
			(effects
				(font
					(size 1.27 1.27)
				)
			)
		)
		(property "Value" "220R3F-1-GP"
			(at -0.0254 -2.5146 180)
			(unlocked yes)
			(layer "F.Fab")
			(hide yes)
			(effects
				(font
					(size 1.016 1.016)
					(thickness 0.1524)
				)
			)
		)
		(property "Device Type" "R603H22"
			(at -0.0254 -4.0386 180)
			(unlocked yes)
			(layer "F.Fab")
			(hide yes)
			(effects
				(font
					(size 1.016 1.016)
					(thickness 0.1524)
				)
			)
		)
		(duplicate_pad_numbers_are_jumpers no)
		(fp_line
			(start 0.2032 0)
			(end 0.4826 0)
			(stroke
				(width 0.2032)
				(type default)
			)
			(layer "F.SilkS")
		)
		(fp_line
			(start -0.4826 0)
			(end -0.2032 0)
			(stroke
				(width 0.2032)
				(type default)
			)
			(layer "F.SilkS")
		)
		(fp_rect
			(start -0.5842 1.3335)
			(end 0.5842 -1.3335)
			(stroke
				(width 0)
				(type default)
			)
			(fill no)
			(layer "F.CrtYd")
		)
		(fp_rect
			(start -0.5842 1.3335)
			(end 0.5842 -1.3335)
			(stroke
				(width 0)
				(type default)
			)
			(fill no)
			(layer "F.Fab")
		)
		(pad "1" smd custom
			(at 0 -0.762 180)
			(size 0.2159 0.2159)
			(layers "F.Cu" "F.Mask" "F.Paste")
			(net "HDD_PRSNT_NET10")
			(options
				(clearance outline)
				(anchor circle)
			)
			(primitives
				(gr_poly
					(pts
						(arc
							(start -0.3302 -0.4318)
							(mid -0.402042 -0.402042)
							(end -0.4318 -0.3302)
						)
						(arc
							(start -0.4318 0.3302)
							(mid -0.402042 0.402042)
							(end -0.3302 0.4318)
						)
						(arc
							(start 0.3302 0.4318)
							(mid 0.402042 0.402042)
							(end 0.4318 0.3302)
						)
						(arc
							(start 0.4318 -0.3302)
							(mid 0.402042 -0.402042)
							(end 0.3302 -0.4318)
						)
					)
					(width 0)
					(fill yes)
				)
			)
		)
		(pad "2" smd custom
			(at 0 0.762 180)
			(size 0.2159 0.2159)
			(layers "F.Cu" "F.Mask" "F.Paste")
			(net "HDD_PRSNT10")
			(options
				(clearance outline)
				(anchor circle)
			)
			(primitives
				(gr_poly
					(pts
						(arc
							(start -0.3302 -0.4318)
							(mid -0.402042 -0.402042)
							(end -0.4318 -0.3302)
						)
						(arc
							(start -0.4318 0.3302)
							(mid -0.402042 0.402042)
							(end -0.3302 0.4318)
						)
						(arc
							(start 0.3302 0.4318)
							(mid 0.402042 0.402042)
							(end 0.4318 0.3302)
						)
						(arc
							(start 0.4318 -0.3302)
							(mid 0.402042 -0.402042)
							(end 0.3302 -0.4318)
						)
					)
					(width 0)
					(fill yes)
				)
			)
		)
	)
	(footprint ""
		(layer "F.Cu")
		(at 58.038492 -83.721956 90)
		(property "Reference" "R236"
			(at 0 0 90)
			(layer "F.SilkS")
			(hide yes)
			(effects
				(font
					(size 1.27 1.27)
				)
			)
		)
		(property "Value" "2R2010J-1-GP"
			(at 0.254 -8.0772 90)
			(unlocked yes)
			(layer "F.Fab")
			(hide yes)
			(effects
				(font
					(size 1.016 1.016)
					(thickness 0.1524)
				)
			)
		)
		(property "Device Type" "R2010H28"
			(at 0.254 -9.6774 90)
			(unlocked yes)
			(layer "F.Fab")
			(hide yes)
			(effects
				(font
					(size 1.016 1.016)
					(thickness 0.1524)
				)
			)
		)
		(duplicate_pad_numbers_are_jumpers no)
		(fp_line
			(start 1.651 -3.302)
			(end -1.651 -3.302)
			(stroke
				(width 0.1524)
				(type default)
			)
			(layer "F.SilkS")
		)
		(fp_line
			(start -1.651 -3.302)
			(end -1.651 3.302)
			(stroke
				(width 0.1524)
				(type default)
			)
			(layer "F.SilkS")
		)
		(fp_line
			(start 1.651 3.302)
			(end 1.651 -3.302)
			(stroke
				(width 0.1524)
				(type default)
			)
			(layer "F.SilkS")
		)
		(fp_line
			(start -1.651 3.302)
			(end 1.651 3.302)
			(stroke
				(width 0.1524)
				(type default)
			)
			(layer "F.SilkS")
		)
		(fp_rect
			(start -1.7272 -3.3782)
			(end 1.7272 3.3782)
			(stroke
				(width 0)
				(type default)
			)
			(fill no)
			(layer "F.CrtYd")
		)
		(fp_poly
			(pts
				(xy 1.7272 3.3782) (xy 1.7272 -3.3782) (xy -1.7272 -3.3782) (xy -1.7272 3.3782)
			)
			(stroke
				(width 0)
				(type default)
			)
			(fill no)
			(layer "F.Fab")
		)
		(pad "1" smd rect
			(at 0 -2.3495 90)
			(size 2.794 1.143)
			(layers "F.Cu" "F.Mask" "F.Paste")
			(net "12V_PRE_9")
		)
		(pad "2" smd rect
			(at 0 2.3495 90)
			(size 2.794 1.143)
			(layers "F.Cu" "F.Mask" "F.Paste")
			(net "P12V_HDD9")
		)
	)
)
